(kicad_pcb
	(version 20260206)
	(generator "pcbnew")
	(generator_version "10.0")
	(general
		(thickness 1.6)
		(legacy_teardrops no)
	)
	(paper "A4")
	(title_block
		(title "Wiwynn_Tioga_Pass_MB.brd")
		(comment 1 "Tioga Pass / footprints 264-269 of 4770")
	)
	(layers
		(0 "F.Cu" signal "TOP")
		(4 "In1.Cu" signal "L2GND")
		(6 "In2.Cu" signal "L3")
		(8 "In3.Cu" signal "L4GND")
		(10 "In4.Cu" signal "L5")
		(12 "In5.Cu" signal "L6GND")
		(14 "In6.Cu" signal "L7VCC")
		(16 "In7.Cu" signal "L8VCC")
		(18 "In8.Cu" signal "L9GND")
		(20 "In9.Cu" signal "L10")
		(22 "In10.Cu" signal "L11GND")
		(24 "In11.Cu" signal "L12")
		(26 "In12.Cu" signal "L13GND")
		(2 "B.Cu" signal "BOTTOM")
		(9 "F.Adhes" user "F.Adhesive")
		(11 "B.Adhes" user "B.Adhesive")
		(13 "F.Paste" user "Package Geometry/Pastemask Top")
		(15 "B.Paste" user "Package Geometry/Pastemask Bottom")
		(5 "F.SilkS" user "Ref Des/Silkscreen Top")
		(7 "B.SilkS" user "Ref Des/Silkscreen Bottom")
		(1 "F.Mask" user "Board Geometry/Soldermask Top")
		(3 "B.Mask" user "Board Geometry/Soldermask Bottom")
		(17 "Dwgs.User" user "User.Drawings")
		(19 "Cmts.User" user "User.Comments")
		(21 "Eco1.User" user "User.Eco1")
		(23 "Eco2.User" user "User.Eco2")
		(25 "Edge.Cuts" user "Board Geometry/Outline")
		(27 "Margin" user)
		(31 "F.CrtYd" user "Package Geometry/Place Bound Top")
		(29 "B.CrtYd" user "Package Geometry/Place Bound Bottom")
		(35 "F.Fab" user "Ref Des/Assembly Top")
		(33 "B.Fab" user "Ref Des/Assembly Bottom")
	)
	(footprint ""
		(layer "F.Cu")
		(at 32.289496 -77.351382 -90)
		(property "Reference" "C1D7"
			(at 0 0 270)
			(layer "F.SilkS")
			(hide yes)
			(effects
				(font
					(size 1.27 1.27)
				)
			)
		)
		(property "Value" ""
			(at 0 0 270)
			(layer "F.Fab")
			(effects
				(font
					(size 1.27 1.27)
				)
			)
		)
		(duplicate_pad_numbers_are_jumpers no)
		(fp_rect
			(start 0.3048 0.9906)
			(end -0.3048 -0.1016)
			(stroke
				(width 0)
				(type default)
			)
			(fill no)
			(layer "F.CrtYd")
		)
		(fp_line
			(start -0.3048 0.9906)
			(end 0.3048 0.9906)
			(stroke
				(width 0.1)
				(type default)
			)
			(layer "F.Fab")
		)
		(fp_line
			(start 0.3048 0.9906)
			(end 0.3048 -0.1016)
			(stroke
				(width 0.1)
				(type default)
			)
			(layer "F.Fab")
		)
		(fp_line
			(start -0.3048 -0.1016)
			(end -0.3048 0.9906)
			(stroke
				(width 0.1)
				(type default)
			)
			(layer "F.Fab")
		)
		(fp_line
			(start 0.3048 -0.1016)
			(end -0.3048 -0.1016)
			(stroke
				(width 0.1)
				(type default)
			)
			(layer "F.Fab")
		)
		(pad "1" smd rect
			(at 0 0 270)
			(size 0.508 0.508)
			(layers "F.Cu" "F.Mask" "F.Paste")
			(net "VR_PVCCIN_CPU1_PH4_VCIN")
		)
		(pad "2" smd rect
			(at 0 0.889 270)
			(size 0.508 0.508)
			(layers "F.Cu" "F.Mask" "F.Paste")
			(net "GND")
		)
		(zone
			(layer "F.Cu")
			(hatch none 0.5)
			(connect_pads
				(clearance 0)
			)
			(min_thickness 0.25)
			(keepout
				(tracks not_allowed)
				(vias allowed)
				(pads allowed)
				(copperpour not_allowed)
				(footprints allowed)
			)
			(placement
				(enabled no)
				(sheetname "")
			)
			(fill
				(thermal_gap 0.5)
				(thermal_bridge_width 0.5)
				(island_removal_mode 0)
			)
			(polygon
				(pts
					(xy 31.654496 -77.097382) (xy 32.035496 -77.097382) (xy 32.035496 -77.605382) (xy 31.654496 -77.605382)
				)
			)
		)
		(zone
			(layer "F.Cu")
			(hatch none 0.5)
			(connect_pads
				(clearance 0)
			)
			(min_thickness 0.25)
			(keepout
				(tracks allowed)
				(vias not_allowed)
				(pads allowed)
				(copperpour not_allowed)
				(footprints allowed)
			)
			(placement
				(enabled no)
				(sheetname "")
			)
			(fill
				(thermal_gap 0.5)
				(thermal_bridge_width 0.5)
				(island_removal_mode 0)
			)
			(polygon
				(pts
					(xy 31.654496 -77.097382) (xy 32.035496 -77.097382) (xy 32.035496 -77.605382) (xy 31.654496 -77.605382)
				)
			)
		)
	)
	(footprint ""
		(layer "F.Cu")
		(at 439.456322 -151.064468 180)
		(property "Reference" "U25W12"
			(at -1.743964 -3.834638 180)
			(unlocked yes)
			(layer "F.SilkS")
			(effects
				(font
					(size 3.048 1.524)
					(thickness 0.000001)
				)
				(justify left)
			)
		)
		(property "Value" ""
			(at 0 0 180)
			(layer "F.Fab")
			(effects
				(font
					(size 1.27 1.27)
				)
			)
		)
		(duplicate_pad_numbers_are_jumpers no)
		(fp_circle
			(center -2.347468 -1.283462)
			(end -2.474468 -1.283462)
			(stroke
				(width 0.254)
				(type default)
			)
			(fill no)
			(layer "F.SilkS")
		)
		(fp_rect
			(start -0.9144 0.9144)
			(end 0.9144 -0.9144)
			(stroke
				(width 0)
				(type default)
			)
			(fill yes)
			(layer "F.Paste")
		)
		(fp_rect
			(start -1.82499 1.82499)
			(end 1.82499 -1.82499)
			(stroke
				(width 0)
				(type default)
			)
			(fill no)
			(layer "F.CrtYd")
		)
		(fp_line
			(start 1.82499 1.82499)
			(end -1.82499 1.82499)
			(stroke
				(width 0.1)
				(type default)
			)
			(layer "F.Fab")
		)
		(fp_line
			(start 1.82499 -1.82499)
			(end 1.82499 1.82499)
			(stroke
				(width 0.1)
				(type default)
			)
			(layer "F.Fab")
		)
		(fp_line
			(start -1.82499 1.82499)
			(end -1.82499 -1.82499)
			(stroke
				(width 0.1)
				(type default)
			)
			(layer "F.Fab")
		)
		(fp_line
			(start -1.82499 -1.82499)
			(end 1.82499 -1.82499)
			(stroke
				(width 0.1)
				(type default)
			)
			(layer "F.Fab")
		)
		(fp_circle
			(center -1.17856 -2.466086)
			(end -1.30556 -2.466086)
			(stroke
				(width 0.254)
				(type default)
			)
			(fill no)
			(layer "F.Fab")
		)
		(pad "1" smd custom
			(at -0.750062 -1.549908 180)
			(size 0.0762 0.0762)
			(layers "F.Cu" "F.Mask" "F.Paste")
			(net "BMC_JTAG_SEL_BUF")
			(options
				(clearance outline)
				(anchor circle)
			)
			(primitives
				(gr_poly
					(pts
						(xy 0.1524 -0.381)
						(arc
							(start 0.1524 0.2286)
							(mid 0 0.381)
							(end -0.1524 0.2286)
						)
						(xy -0.1524 -0.381)
					)
					(width 0)
					(fill yes)
				)
			)
		)
		(pad "2" smd custom
			(at -1.549908 -0.999998 180)
			(size 0.0762 0.0762)
			(layers "F.Cu" "F.Mask" "F.Paste")
			(net "BMC_PREQ_N")
			(options
				(clearance outline)
				(anchor circle)
			)
			(primitives
				(gr_poly
					(pts
						(xy -0.381 -0.1524)
						(arc
							(start 0.2286 -0.1524)
							(mid 0.381 0)
							(end 0.2286 0.1524)
						)
						(xy -0.381 0.1524)
					)
					(width 0)
					(fill yes)
				)
			)
		)
		(pad "3" smd custom
			(at -1.549908 -0.500126 180)
			(size 0.0762 0.0762)
			(layers "F.Cu" "F.Mask" "F.Paste")
			(net "BMC_PREQ_BUF_N")
			(options
				(clearance outline)
				(anchor circle)
			)
			(primitives
				(gr_poly
					(pts
						(xy -0.381 -0.1524)
						(arc
							(start 0.2286 -0.1524)
							(mid 0.381 0)
							(end 0.2286 0.1524)
						)
						(xy -0.381 0.1524)
					)
					(width 0)
					(fill yes)
				)
			)
		)
		(pad "4" smd custom
			(at -1.549908 0 180)
			(size 0.0762 0.0762)
			(layers "F.Cu" "F.Mask" "F.Paste")
			(net "JTAG_BMC_TCK0")
			(options
				(clearance outline)
				(anchor circle)
			)
			(primitives
				(gr_poly
					(pts
						(xy -0.381 -0.1524)
						(arc
							(start 0.2286 -0.1524)
							(mid 0.381 0)
							(end 0.2286 0.1524)
						)
						(xy -0.381 0.1524)
					)
					(width 0)
					(fill yes)
				)
			)
		)
		(pad "5" smd custom
			(at -1.549908 0.500126 180)
			(size 0.0762 0.0762)
			(layers "F.Cu" "F.Mask" "F.Paste")
			(net "P1V05_PCH_STBY")
			(options
				(clearance outline)
				(anchor circle)
			)
			(primitives
				(gr_poly
					(pts
						(xy -0.381 -0.1524)
						(arc
							(start 0.2286 -0.1524)
							(mid 0.381 0)
							(end 0.2286 0.1524)
						)
						(xy -0.381 0.1524)
					)
					(width 0)
					(fill yes)
				)
			)
		)
		(pad "6" smd custom
			(at -1.549908 0.999998 180)
			(size 0.0762 0.0762)
			(layers "F.Cu" "F.Mask" "F.Paste")
			(net "XDP_CPU_TCK0_R")
			(options
				(clearance outline)
				(anchor circle)
			)
			(primitives
				(gr_poly
					(pts
						(xy -0.381 -0.1524)
						(arc
							(start 0.2286 -0.1524)
							(mid 0.381 0)
							(end 0.2286 0.1524)
						)
						(xy -0.381 0.1524)
					)
					(width 0)
					(fill yes)
				)
			)
		)
		(pad "7" smd custom
			(at -0.750062 1.549908 180)
			(size 0.0762 0.0762)
			(layers "F.Cu" "F.Mask" "F.Paste")
			(net "GND")
			(options
				(clearance outline)
				(anchor circle)
			)
			(primitives
				(gr_poly
					(pts
						(xy -0.1524 0.381)
						(arc
							(start -0.1524 -0.2286)
							(mid 0 -0.381)
							(end 0.1524 -0.2286)
						)
						(xy 0.1524 0.381)
					)
					(width 0)
					(fill yes)
				)
			)
		)
		(pad "8" smd custom
			(at 0.769874 1.549908 180)
			(size 0.0762 0.0762)
			(layers "F.Cu" "F.Mask" "F.Paste")
			(net "XDP_PCH_TCK1_R")
			(options
				(clearance outline)
				(anchor circle)
			)
			(primitives
				(gr_poly
					(pts
						(xy -0.1524 0.381)
						(arc
							(start -0.1524 -0.2286)
							(mid 0 -0.381)
							(end 0.1524 -0.2286)
						)
						(xy 0.1524 0.381)
					)
					(width 0)
					(fill yes)
				)
			)
		)
		(pad "9" smd custom
			(at 1.549908 0.999998 180)
			(size 0.0762 0.0762)
			(layers "F.Cu" "F.Mask" "F.Paste")
			(net "P1V05_PCH_STBY")
			(options
				(clearance outline)
				(anchor circle)
			)
			(primitives
				(gr_poly
					(pts
						(xy 0.381 0.1524)
						(arc
							(start -0.2286 0.1524)
							(mid -0.381 0)
							(end -0.2286 -0.1524)
						)
						(xy 0.381 -0.1524)
					)
					(width 0)
					(fill yes)
				)
			)
		)
		(pad "10" smd custom
			(at 1.549908 0.500126 180)
			(size 0.0762 0.0762)
			(layers "F.Cu" "F.Mask" "F.Paste")
			(net "JTAG_BMC_TCK1")
			(options
				(clearance outline)
				(anchor circle)
			)
			(primitives
				(gr_poly
					(pts
						(xy 0.381 0.1524)
						(arc
							(start -0.2286 0.1524)
							(mid -0.381 0)
							(end -0.2286 -0.1524)
						)
						(xy 0.381 -0.1524)
					)
					(width 0)
					(fill yes)
				)
			)
		)
		(pad "11" smd custom
			(at 1.549908 0 180)
			(size 0.0762 0.0762)
			(layers "F.Cu" "F.Mask" "F.Paste")
			(net "XDP_TRST_R_N")
			(options
				(clearance outline)
				(anchor circle)
			)
			(primitives
				(gr_poly
					(pts
						(xy 0.381 0.1524)
						(arc
							(start -0.2286 0.1524)
							(mid -0.381 0)
							(end -0.2286 -0.1524)
						)
						(xy 0.381 -0.1524)
					)
					(width 0)
					(fill yes)
				)
			)
		)
		(pad "12" smd custom
			(at 1.549908 -0.500126 180)
			(size 0.0762 0.0762)
			(layers "F.Cu" "F.Mask" "F.Paste")
			(net "P1V05_PCH_STBY")
			(options
				(clearance outline)
				(anchor circle)
			)
			(primitives
				(gr_poly
					(pts
						(xy 0.381 0.1524)
						(arc
							(start -0.2286 0.1524)
							(mid -0.381 0)
							(end -0.2286 -0.1524)
						)
						(xy 0.381 -0.1524)
					)
					(width 0)
					(fill yes)
				)
			)
		)
		(pad "13" smd custom
			(at 1.549908 -0.999998 180)
			(size 0.0762 0.0762)
			(layers "F.Cu" "F.Mask" "F.Paste")
			(net "JTAG_BMC_TRST_BUF_N")
			(options
				(clearance outline)
				(anchor circle)
			)
			(primitives
				(gr_poly
					(pts
						(xy 0.381 0.1524)
						(arc
							(start -0.2286 0.1524)
							(mid -0.381 0)
							(end -0.2286 -0.1524)
						)
						(xy 0.381 -0.1524)
					)
					(width 0)
					(fill yes)
				)
			)
		)
		(pad "14" smd custom
			(at 0.750062 -1.549908 180)
			(size 0.0762 0.0762)
			(layers "F.Cu" "F.Mask" "F.Paste")
			(net "P3V3_STBY")
			(options
				(clearance outline)
				(anchor circle)
			)
			(primitives
				(gr_poly
					(pts
						(xy 0.1524 -0.381)
						(arc
							(start 0.1524 0.2286)
							(mid 0 0.381)
							(end -0.1524 0.2286)
						)
						(xy -0.1524 -0.381)
					)
					(width 0)
					(fill yes)
				)
			)
		)
		(pad "15" smd rect
			(at 0 0 180)
			(size 1.8288 1.8288)
			(layers "F.Cu" "F.Mask" "F.Paste")
			(net "GND")
		)
	)
	(footprint ""
		(layer "F.Cu")
		(at 153.4922 -140.0048 -90)
		(property "Reference" "C3A7"
			(at 0 0 270)
			(layer "F.SilkS")
			(hide yes)
			(effects
				(font
					(size 1.27 1.27)
				)
			)
		)
		(property "Value" ""
			(at 0 0 270)
			(layer "F.Fab")
			(effects
				(font
					(size 1.27 1.27)
				)
			)
		)
		(duplicate_pad_numbers_are_jumpers no)
		(fp_rect
			(start -0.4953 1.6002)
			(end 0.4953 -0.2032)
			(stroke
				(width 0)
				(type default)
			)
			(fill no)
			(layer "F.CrtYd")
		)
		(fp_line
			(start -0.4953 1.6002)
			(end -0.4953 -0.2032)
			(stroke
				(width 0.1)
				(type default)
			)
			(layer "F.Fab")
		)
		(fp_line
			(start 0.4953 1.6002)
			(end -0.4953 1.6002)
			(stroke
				(width 0.1)
				(type default)
			)
			(layer "F.Fab")
		)
		(fp_line
			(start -0.4953 -0.2032)
			(end 0.4953 -0.2032)
			(stroke
				(width 0.1)
				(type default)
			)
			(layer "F.Fab")
		)
		(fp_line
			(start 0.4953 -0.2032)
			(end 0.4953 1.6002)
			(stroke
				(width 0.1)
				(type default)
			)
			(layer "F.Fab")
		)
		(pad "1" smd rect
			(at 0 0 270)
			(size 0.762 0.889)
			(layers "F.Cu" "F.Mask" "F.Paste")
			(net "PVPP_KLM")
		)
		(pad "2" smd rect
			(at 0 1.397 270)
			(size 0.762 0.889)
			(layers "F.Cu" "F.Mask" "F.Paste")
			(net "GND")
		)
		(zone
			(layer "F.Cu")
			(hatch none 0.5)
			(connect_pads
				(clearance 0)
			)
			(min_thickness 0.25)
			(keepout
				(tracks not_allowed)
				(vias allowed)
				(pads allowed)
				(copperpour not_allowed)
				(footprints allowed)
			)
			(placement
				(enabled no)
				(sheetname "")
			)
			(fill
				(thermal_gap 0.5)
				(thermal_bridge_width 0.5)
				(island_removal_mode 0)
			)
			(polygon
				(pts
					(xy 152.5397 -140.3858) (xy 152.5397 -139.6238) (xy 153.0477 -139.6238) (xy 153.0477 -140.3858)
				)
			)
		)
	)
	(footprint ""
		(layer "F.Cu")
		(at 12.446 -102.0064)
		(property "Reference" "R1C31"
			(at 0 0 0)
			(layer "F.SilkS")
			(hide yes)
			(effects
				(font
					(size 1.27 1.27)
				)
			)
		)
		(property "Value" ""
			(at 0 0 0)
			(layer "F.Fab")
			(effects
				(font
					(size 1.27 1.27)
				)
			)
		)
		(duplicate_pad_numbers_are_jumpers no)
		(fp_poly
			(pts
				(xy -0.2794 -0.1016) (xy 0.2794 -0.1016) (xy 0.2794 0.9906) (xy -0.2794 0.9906)
			)
			(stroke
				(width 0)
				(type default)
			)
			(fill no)
			(layer "F.CrtYd")
		)
		(fp_line
			(start -0.2794 -0.1016)
			(end -0.2794 0.9906)
			(stroke
				(width 0.1)
				(type default)
			)
			(layer "F.Fab")
		)
		(fp_line
			(start -0.2794 0.9906)
			(end 0.2794 0.9906)
			(stroke
				(width 0.1)
				(type default)
			)
			(layer "F.Fab")
		)
		(fp_line
			(start 0.2794 -0.1016)
			(end -0.2794 -0.1016)
			(stroke
				(width 0.1)
				(type default)
			)
			(layer "F.Fab")
		)
		(fp_line
			(start 0.2794 0.9906)
			(end 0.2794 -0.1016)
			(stroke
				(width 0.1)
				(type default)
			)
			(layer "F.Fab")
		)
		(pad "1" smd rect
			(at 0 0)
			(size 0.508 0.508)
			(layers "F.Cu" "F.Mask" "F.Paste")
			(net "FM_XRC_READY_N")
		)
		(pad "2" smd rect
			(at 0 0.889)
			(size 0.508 0.508)
			(layers "F.Cu" "F.Mask" "F.Paste")
			(net "FAN_TACH0_R")
		)
		(zone
			(layer "F.Cu")
			(hatch none 0.5)
			(connect_pads
				(clearance 0)
			)
			(min_thickness 0.25)
			(keepout
				(tracks allowed)
				(vias not_allowed)
				(pads allowed)
				(copperpour not_allowed)
				(footprints allowed)
			)
			(placement
				(enabled no)
				(sheetname "")
			)
			(fill
				(thermal_gap 0.5)
				(thermal_bridge_width 0.5)
				(island_removal_mode 0)
			)
			(polygon
				(pts
					(xy 12.192 -101.7524) (xy 12.7 -101.7524) (xy 12.7 -101.3714) (xy 12.192 -101.3714)
				)
			)
		)
		(zone
			(layer "F.Cu")
			(hatch none 0.5)
			(connect_pads
				(clearance 0)
			)
			(min_thickness 0.25)
			(keepout
				(tracks not_allowed)
				(vias allowed)
				(pads allowed)
				(copperpour not_allowed)
				(footprints allowed)
			)
			(placement
				(enabled no)
				(sheetname "")
			)
			(fill
				(thermal_gap 0.5)
				(thermal_bridge_width 0.5)
				(island_removal_mode 0)
			)
			(polygon
				(pts
					(xy 12.192 -101.3714) (xy 12.7 -101.3714) (xy 12.7 -101.7524) (xy 12.192 -101.7524)
				)
			)
		)
	)
	(footprint ""
		(layer "F.Cu")
		(at 26.2255 -66.46672 180)
		(property "Reference" "R1D51"
			(at 0 0 180)
			(layer "F.SilkS")
			(hide yes)
			(effects
				(font
					(size 1.27 1.27)
				)
			)
		)
		(property "Value" ""
			(at 0 0 180)
			(layer "F.Fab")
			(effects
				(font
					(size 1.27 1.27)
				)
			)
		)
		(duplicate_pad_numbers_are_jumpers no)
		(fp_poly
			(pts
				(xy -0.2794 -0.1016) (xy 0.2794 -0.1016) (xy 0.2794 0.9906) (xy -0.2794 0.9906)
			)
			(stroke
				(width 0)
				(type default)
			)
			(fill no)
			(layer "F.CrtYd")
		)
		(fp_line
			(start 0.2794 0.9906)
			(end 0.2794 -0.1016)
			(stroke
				(width 0.1)
				(type default)
			)
			(layer "F.Fab")
		)
		(fp_line
			(start 0.2794 -0.1016)
			(end -0.2794 -0.1016)
			(stroke
				(width 0.1)
				(type default)
			)
			(layer "F.Fab")
		)
		(fp_line
			(start -0.2794 0.9906)
			(end 0.2794 0.9906)
			(stroke
				(width 0.1)
				(type default)
			)
			(layer "F.Fab")
		)
		(fp_line
			(start -0.2794 -0.1016)
			(end -0.2794 0.9906)
			(stroke
				(width 0.1)
				(type default)
			)
			(layer "F.Fab")
		)
		(pad "1" smd rect
			(at 0 0 180)
			(size 0.508 0.508)
			(layers "F.Cu" "F.Mask" "F.Paste")
			(net "A_HSC_C")
		)
		(pad "2" smd rect
			(at 0 0.889 180)
			(size 0.508 0.508)
			(layers "F.Cu" "F.Mask" "F.Paste")
			(net "A_HSC_GATE")
		)
		(zone
			(layer "F.Cu")
			(hatch none 0.5)
			(connect_pads
				(clearance 0)
			)
			(min_thickness 0.25)
			(keepout
				(tracks not_allowed)
				(vias allowed)
				(pads allowed)
				(copperpour not_allowed)
				(footprints allowed)
			)
			(placement
				(enabled no)
				(sheetname "")
			)
			(fill
				(thermal_gap 0.5)
				(thermal_bridge_width 0.5)
				(island_removal_mode 0)
			)
			(polygon
				(pts
					(xy 26.4795 -67.10172) (xy 25.9715 -67.10172) (xy 25.9715 -66.72072) (xy 26.4795 -66.72072)
				)
			)
		)
		(zone
			(layer "F.Cu")
			(hatch none 0.5)
			(connect_pads
				(clearance 0)
			)
			(min_thickness 0.25)
			(keepout
				(tracks allowed)
				(vias not_allowed)
				(pads allowed)
				(copperpour not_allowed)
				(footprints allowed)
			)
			(placement
				(enabled no)
				(sheetname "")
			)
			(fill
				(thermal_gap 0.5)
				(thermal_bridge_width 0.5)
				(island_removal_mode 0)
			)
			(polygon
				(pts
					(xy 26.4795 -66.72072) (xy 25.9715 -66.72072) (xy 25.9715 -67.10172) (xy 26.4795 -67.10172)
				)
			)
		)
	)
	(footprint ""
		(layer "F.Cu")
		(at 381.4572 -141.7447 90)
		(property "Reference" "C3M6"
			(at 0 0 90)
			(layer "F.SilkS")
			(hide yes)
			(effects
				(font
					(size 1.27 1.27)
				)
			)
		)
		(property "Value" ""
			(at 0 0 90)
			(layer "F.Fab")
			(effects
				(font
					(size 1.27 1.27)
				)
			)
		)
		(duplicate_pad_numbers_are_jumpers no)
		(fp_rect
			(start -0.4953 -0.2032)
			(end 0.4953 1.6002)
			(stroke
				(width 0)
				(type default)
			)
			(fill no)
			(layer "F.CrtYd")
		)
		(fp_line
			(start 0.4953 -0.2032)
			(end 0.4953 1.6002)
			(stroke
				(width 0.1)
				(type default)
			)
			(layer "F.Fab")
		)
		(fp_line
			(start -0.4953 -0.2032)
			(end 0.4953 -0.2032)
			(stroke
				(width 0.1)
				(type default)
			)
			(layer "F.Fab")
		)
		(fp_line
			(start 0.4953 1.6002)
			(end -0.4953 1.6002)
			(stroke
				(width 0.1)
				(type default)
			)
			(layer "F.Fab")
		)
		(fp_line
			(start -0.4953 1.6002)
			(end -0.4953 -0.2032)
			(stroke
				(width 0.1)
				(type default)
			)
			(layer "F.Fab")
		)
		(pad "1" smd rect
			(at 0 0 90)
			(size 0.762 0.889)
			(layers "F.Cu" "F.Mask" "F.Paste")
			(net "PVNN_PCH_STBY")
		)
		(pad "2" smd rect
			(at 0 1.397 90)
			(size 0.762 0.889)
			(layers "F.Cu" "F.Mask" "F.Paste")
			(net "GND")
		)
		(zone
			(layer "F.Cu")
			(hatch none 0.5)
			(connect_pads
				(clearance 0)
			)
			(min_thickness 0.25)
			(keepout
				(tracks not_allowed)
				(vias allowed)
				(pads allowed)
				(copperpour not_allowed)
				(footprints allowed)
			)
			(placement
				(enabled no)
				(sheetname "")
			)
			(fill
				(thermal_gap 0.5)
				(thermal_bridge_width 0.5)
				(island_removal_mode 0)
			)
			(polygon
				(pts
					(xy 381.9017 -141.3637) (xy 382.4097 -141.3637) (xy 382.4097 -142.1257) (xy 381.9017 -142.1257)
				)
			)
		)
	)
)
